# T6G (Grand Teton) — schematic netlist excerpt (pin names and nets, part order shuffled) for the footprints in the layout excerpt that follows; sources: Cadence DE-HDL packaged netlist, KiCad conversion of 04192023_DAF0TMB3IC0_F0TG_MB_C_brd_V02_OCP.brd

PR391  Q_RES  1K 1% EMPTY  pkg 0402LF  page 224 : A = PVDD11_S3_P1_RESET_N_R ; B = PVDD18_S5_P1

PU205  MP5016GQHLZ  MP5016GQH-L-Z IC  pkg QFN8_2X1-5  page 135
  VCC  = P3V3_AUX
  GND  = GND
  ILIMIT  = P3V3_OCP_ILIMIT_1
  MODE  = P3V3_OCP_MODE_1
  SOURCE  = P3V3_OCP_SFF_R
  GATE  = P3V3_OCP_GATE_1
  EN  = P3V3_OCP_EN_1_R2
  DV_DT  = P3V3_OCP_DVDT_1

C6720  Q_CAP_DIFFBUS  DIFF BUS_0.22UF 6.3V 20% X6S  pkg C0201  page 341 : \1\ = P5E_CPU1_P2_TX_BUF_C_DN<13> ; \2\ = P5E_CPU1_P2_TX_BUF_DN<13>

(kicad_pcb
	(version 20260206)
	(generator "pcbnew")
	(generator_version "10.0")
	(general
		(thickness 1.6)
		(legacy_teardrops no)
	)
	(paper "A4")
	(title_block
		(title "04192023_DAF0TMB3IC0_F0TG_MB_C_brd_V02_OCP.brd")
		(comment 1 "Grand Teton / footprints 4409-4411 of 8354")
	)
	(layers
		(0 "F.Cu" signal "TOP")
		(4 "In1.Cu" signal "GND")
		(6 "In2.Cu" signal "IN1")
		(8 "In3.Cu" signal "GND1")
		(10 "In4.Cu" signal "IN2")
		(12 "In5.Cu" signal "GND2")
		(14 "In6.Cu" signal "IN3")
		(16 "In7.Cu" signal "GND3")
		(18 "In8.Cu" signal "VCC")
		(20 "In9.Cu" signal "VCC1")
		(22 "In10.Cu" signal "GND4")
		(24 "In11.Cu" signal "IN4")
		(26 "In12.Cu" signal "GND5")
		(28 "In13.Cu" signal "IN5")
		(30 "In14.Cu" signal "GND6")
		(32 "In15.Cu" signal "IN6")
		(34 "In16.Cu" signal "GND7")
		(2 "B.Cu" signal "BOTTOM")
		(9 "F.Adhes" user "F.Adhesive")
		(11 "B.Adhes" user "B.Adhesive")
		(13 "F.Paste" user "Package Geometry/Pastemask Top")
		(15 "B.Paste" user "Package Geometry/Pastemask Bottom")
		(5 "F.SilkS" user "Ref Des/Silkscreen Top")
		(7 "B.SilkS" user "Ref Des/Silkscreen Bottom")
		(1 "F.Mask" user "Board Geometry/Soldermask Top")
		(3 "B.Mask" user "Board Geometry/Soldermask Bottom")
		(17 "Dwgs.User" user "User.Drawings")
		(19 "Cmts.User" user "User.Comments")
		(21 "Eco1.User" user "User.Eco1")
		(23 "Eco2.User" user "User.Eco2")
		(25 "Edge.Cuts" user "Board Geometry/Outline")
		(27 "Margin" user)
		(31 "F.CrtYd" user "Package Geometry/Place Bound Top")
		(29 "B.CrtYd" user "Package Geometry/Place Bound Bottom")
		(35 "F.Fab" user "Ref Des/Assembly Top")
		(33 "B.Fab" user "Ref Des/Assembly Bottom")
	)
	(footprint ""
		(layer "F.Cu")
		(at 420.52494 -105.207308)
		(property "Reference" "PU205"
			(at -5.431282 -0.11684 90)
			(unlocked yes)
			(layer "F.SilkS")
			(effects
				(font
					(size 0.7874 0.5842)
					(thickness 0.1524)
				)
			)
		)
		(property "Value" ""
			(at 0 0 0)
			(layer "F.Fab")
			(effects
				(font
					(size 1.27 1.27)
				)
			)
		)
		(duplicate_pad_numbers_are_jumpers no)
		(fp_line
			(start -1.239774 -1.495298)
			(end 1.239774 -1.495298)
			(stroke
				(width 0.1524)
				(type default)
			)
			(layer "F.SilkS")
		)
		(fp_line
			(start -1.239774 1.495298)
			(end -1.239774 -1.495298)
			(stroke
				(width 0.1524)
				(type default)
			)
			(layer "F.SilkS")
		)
		(fp_line
			(start 1.239774 -1.495298)
			(end 1.239774 1.495298)
			(stroke
				(width 0.1524)
				(type default)
			)
			(layer "F.SilkS")
		)
		(fp_line
			(start 1.239774 1.495298)
			(end -1.239774 1.495298)
			(stroke
				(width 0.1524)
				(type default)
			)
			(layer "F.SilkS")
		)
		(fp_poly
			(pts
				(xy -1.827784 -0.742188) (xy -2.962402 -0.79629) (xy -2.465324 -1.682496)
			)
			(stroke
				(width 0)
				(type default)
			)
			(fill yes)
			(layer "F.SilkS")
		)
		(fp_line
			(start -0.8001 -1.050036)
			(end 0.8001 -1.050036)
			(stroke
				(width 0.1)
				(type default)
			)
			(layer "F.Fab")
		)
		(fp_line
			(start -0.8001 1.050036)
			(end -0.8001 -1.050036)
			(stroke
				(width 0.1)
				(type default)
			)
			(layer "F.Fab")
		)
		(fp_line
			(start 0.8001 -1.050036)
			(end 0.8001 1.050036)
			(stroke
				(width 0.1)
				(type default)
			)
			(layer "F.Fab")
		)
		(fp_line
			(start 0.8001 1.050036)
			(end -0.8001 1.050036)
			(stroke
				(width 0.1)
				(type default)
			)
			(layer "F.Fab")
		)
		(fp_poly
			(pts
				(xy -2.458974 -0.508) (xy -2.458974 0.508) (xy -1.442974 0)
			)
			(stroke
				(width 0)
				(type default)
			)
			(fill yes)
			(layer "F.Fab")
		)
		(pad "1_2" smd circle
			(at -0.374904 0 90)
			(size 0 0)
			(layers "F.Cu" "F.Mask" "F.Paste")
			(net "P3V3_AUX")
		)
		(pad "3" smd rect
			(at -0.499872 0.999998)
			(size 0.254 0.7112)
			(layers "F.Cu" "F.Mask" "F.Paste")
			(net "GND")
		)
		(pad "4" smd rect
			(at 0 0.999998)
			(size 0.254 0.7112)
			(layers "F.Cu" "F.Mask" "F.Paste")
			(net "P3V3_OCP_ILIMIT_1")
		)
		(pad "5" smd rect
			(at 0.499872 0.999998)
			(size 0.254 0.7112)
			(layers "F.Cu" "F.Mask" "F.Paste")
			(net "P3V3_OCP_MODE_1")
		)
		(pad "6_7" smd circle
			(at 0.374904 0 270)
			(size 0 0)
			(layers "F.Cu" "F.Mask" "F.Paste")
			(net "P3V3_OCP_SFF_R")
		)
		(pad "8" smd rect
			(at 0.499872 -0.999998)
			(size 0.254 0.7112)
			(layers "F.Cu" "F.Mask" "F.Paste")
			(net "P3V3_OCP_GATE_1")
		)
		(pad "9" smd rect
			(at 0 -0.999998)
			(size 0.254 0.7112)
			(layers "F.Cu" "F.Mask" "F.Paste")
			(net "P3V3_OCP_EN_1_R2")
		)
		(pad "10" smd rect
			(at -0.499872 -0.999998)
			(size 0.254 0.7112)
			(layers "F.Cu" "F.Mask" "F.Paste")
			(net "P3V3_OCP_DVDT_1")
		)
	)
	(footprint ""
		(layer "F.Cu")
		(at 157.686502 -349.270828 180)
		(property "Reference" "PR391"
			(at 0 0 180)
			(layer "F.SilkS")
			(hide yes)
			(effects
				(font
					(size 1.27 1.27)
				)
			)
		)
		(property "Value" ""
			(at 0 0 180)
			(layer "F.Fab")
			(effects
				(font
					(size 1.27 1.27)
				)
			)
		)
		(duplicate_pad_numbers_are_jumpers no)
		(fp_line
			(start 0.7874 0.4064)
			(end -0.7874 0.4064)
			(stroke
				(width 0.1524)
				(type default)
			)
			(layer "F.SilkS")
		)
		(fp_line
			(start 0.7874 -0.4064)
			(end 0.7874 0.4064)
			(stroke
				(width 0.1524)
				(type default)
			)
			(layer "F.SilkS")
		)
		(fp_line
			(start -0.7874 0.4064)
			(end -0.7874 -0.4064)
			(stroke
				(width 0.1524)
				(type default)
			)
			(layer "F.SilkS")
		)
		(fp_line
			(start -0.7874 -0.4064)
			(end 0.7874 -0.4064)
			(stroke
				(width 0.1524)
				(type default)
			)
			(layer "F.SilkS")
		)
		(fp_line
			(start 0.67945 0.3048)
			(end 0.120396 0.3048)
			(stroke
				(width 0.1)
				(type default)
			)
			(layer "F.Fab")
		)
		(fp_line
			(start 0.67945 -0.3048)
			(end 0.67945 0.3048)
			(stroke
				(width 0.1)
				(type default)
			)
			(layer "F.Fab")
		)
		(fp_line
			(start 0.12065 -0.2794)
			(end 0.12065 -0.3048)
			(stroke
				(width 0.1)
				(type default)
			)
			(layer "F.Fab")
		)
		(fp_line
			(start 0.12065 -0.3048)
			(end 0.67945 -0.3048)
			(stroke
				(width 0.1)
				(type default)
			)
			(layer "F.Fab")
		)
		(fp_line
			(start 0.120396 0.3048)
			(end 0.120396 0.2794)
			(stroke
				(width 0.1)
				(type default)
			)
			(layer "F.Fab")
		)
		(fp_line
			(start 0.120396 0.2794)
			(end -0.12065 0.2794)
			(stroke
				(width 0.1)
				(type default)
			)
			(layer "F.Fab")
		)
		(fp_line
			(start -0.12065 0.3048)
			(end -0.67945 0.3048)
			(stroke
				(width 0.1)
				(type default)
			)
			(layer "F.Fab")
		)
		(fp_line
			(start -0.12065 0.2794)
			(end -0.12065 0.3048)
			(stroke
				(width 0.1)
				(type default)
			)
			(layer "F.Fab")
		)
		(fp_line
			(start -0.12065 -0.2794)
			(end 0.12065 -0.2794)
			(stroke
				(width 0.1)
				(type default)
			)
			(layer "F.Fab")
		)
		(fp_line
			(start -0.12065 -0.305054)
			(end -0.12065 -0.2794)
			(stroke
				(width 0.1)
				(type default)
			)
			(layer "F.Fab")
		)
		(fp_line
			(start -0.67945 0.3048)
			(end -0.67945 -0.305054)
			(stroke
				(width 0.1)
				(type default)
			)
			(layer "F.Fab")
		)
		(fp_line
			(start -0.67945 -0.305054)
			(end -0.12065 -0.305054)
			(stroke
				(width 0.1)
				(type default)
			)
			(layer "F.Fab")
		)
		(pad "1" smd circle
			(at -0.40005 0 180)
			(size 0 0)
			(layers "F.Cu" "F.Mask" "F.Paste")
			(net "PVDD11_S3_P1_RESET_N_R")
		)
		(pad "2" smd circle
			(at 0.40005 0 180)
			(size 0 0)
			(layers "F.Cu" "F.Mask" "F.Paste")
			(net "PVDD18_S5_P1")
		)
	)
	(footprint ""
		(layer "F.Cu")
		(at 154.690826 -408.517344 -90)
		(property "Reference" "C6720"
			(at 0 0 270)
			(layer "F.SilkS")
			(hide yes)
			(effects
				(font
					(size 1.27 1.27)
				)
			)
		)
		(property "Value" ""
			(at 0 0 270)
			(layer "F.Fab")
			(effects
				(font
					(size 1.27 1.27)
				)
			)
		)
		(duplicate_pad_numbers_are_jumpers no)
		(fp_line
			(start -0.299974 0.150114)
			(end -0.299974 -0.150114)
			(stroke
				(width 0.1)
				(type default)
			)
			(layer "F.Fab")
		)
		(fp_line
			(start 0.299974 0.150114)
			(end -0.299974 0.150114)
			(stroke
				(width 0.1)
				(type default)
			)
			(layer "F.Fab")
		)
		(fp_line
			(start -0.299974 -0.150114)
			(end 0.299974 -0.150114)
			(stroke
				(width 0.1)
				(type default)
			)
			(layer "F.Fab")
		)
		(fp_line
			(start 0.299974 -0.150114)
			(end 0.299974 0.150114)
			(stroke
				(width 0.1)
				(type default)
			)
			(layer "F.Fab")
		)
		(pad "1" smd rect
			(at -0.2667 0 270)
			(size 0.3048 0.381)
			(layers "F.Cu" "F.Mask" "F.Paste")
			(net "P5E_CPU1_P2_TX_BUF_C_DN<13>")
		)
		(pad "2" smd rect
			(at 0.2667 0 270)
			(size 0.3048 0.381)
			(layers "F.Cu" "F.Mask" "F.Paste")
			(net "P5E_CPU1_P2_TX_BUF_DN<13>")
		)
	)
)
